# S9S_MB_2U (Grand Teton) — schematic netlist excerpt (pin names and nets, part order shuffled) for the footprints in the layout excerpt that follows; sources: Cadence DE-HDL packaged netlist, KiCad conversion of 03242023_DA0F0TMBIJ0_F0T_Motherboard_J_brd_V01_OCP.brd

J11  SCONN288_ADR50017P130CC  SCONN288_ADR50017-P130CC IO  pkg DDR288S_1-1VXB  page 92
  VIN_BULK0  = P12V_S3_AUX_CPU0_NVDIMM
  RFU0  = TP_CHF_CPU0_DIMM1_FRU_0
  VIN_MGMT  = P3V3_AUX
  HSCL  = I3C_SPD_DDREFGH_CPU0_LVC1_SCL_2
  HSDA  = I3C_SPD_DDREFGH_CPU0_LVC1_SDA
  VSS0  = GND
  DQ0_A  = M_F_CPU0_SA_DQ<0>
  VSS1  = GND
  DQ1_A  = M_F_CPU0_SA_DQ<1>
  VSS2  = GND
  DQS0_A_T  = M_F_CPU0_SA_DQS_DP<0>
  DQS0_A_C  = M_F_CPU0_SA_DQS_DN<0>
  VSS3  = GND
  DQ4_A  = M_F_CPU0_SA_DQ<4>
  VSS4  = GND
  DQ5_A  = M_F_CPU0_SA_DQ<5>
  VSS5  = GND
  DQ8_A  = M_F_CPU0_SA_DQ<8>
  VSS6  = GND
  DQ9_A  = M_F_CPU0_SA_DQ<9>
  VSS7  = GND
  DQS1_A_T  = M_F_CPU0_SA_DQS_DP<1>
  DQS1_A_C  = M_F_CPU0_SA_DQS_DN<1>
  VSS8  = GND
  DQ12_A  = M_F_CPU0_SA_DQ<12>
  VSS9  = GND
  DQ13_A  = M_F_CPU0_SA_DQ<13>
  VSS10  = GND
  DQ16_A  = M_F_CPU0_SA_DQ<16>
  VSS11  = GND
  DQ17_A  = M_F_CPU0_SA_DQ<17>
  VSS12  = GND
  DQS2_A_T  = M_F_CPU0_SA_DQS_DP<2>
  DQS2_A_C  = M_F_CPU0_SA_DQS_DN<2>
  VSS13  = GND
  DQ20_A  = M_F_CPU0_SA_DQ<20>
  VSS14  = GND
  DQ21_A  = M_F_CPU0_SA_DQ<21>
  VSS15  = GND
  DQ24_A  = M_F_CPU0_SA_DQ<24>
  VSS16  = GND
  DQ25_A  = M_F_CPU0_SA_DQ<25>
  VSS17  = GND
  DQS3_A_T  = M_F_CPU0_SA_DQS_DP<3>
  DQS3_A_C  = M_F_CPU0_SA_DQS_DN<3>
  VSS18  = GND
  DQ28_A  = M_F_CPU0_SA_DQ<28>
  VSS19  = GND
  DQ29_A  = M_F_CPU0_SA_DQ<29>
  VSS20  = GND
  CB0_A  = M_F_CPU0_SA_CB<0>
  VSS21  = GND
  CB1_A  = M_F_CPU0_SA_CB<1>
  VSS22  = GND
  DQS4_A_T  = M_F_CPU0_SA_DQS_DP<4>
  DQS4_A_C  = M_F_CPU0_SA_DQS_DN<4>
  VSS23  = GND
  CB4_A  = M_F_CPU0_SA_CB<4>
  VSS24  = GND
  CB5_A  = M_F_CPU0_SA_CB<5>
  VSS25  = GND
  ALERT_N  = M_F_CPU0_ALERT_N
  VSS26  = GND
  CS0_A_N  = M_F_CPU0_SA_CS_N<0>
  VSS27  = GND
  CA0_A  = M_F_CPU0_SA_CA<0>
  VSS28  = GND
  CA2_A  = M_F_CPU0_SA_CA<2>
  VSS29  = GND
  CA4_A  = M_F_CPU0_SA_CA<4>
  VSS30  = GND
  CA6_A  = M_F_CPU0_SA_CA<6>
  VSS31  = GND
  PAR_A  = M_F_CPU0_SA_PAR
  VSS32  = GND
  CA0_B  = M_F_CPU0_SB_CA<0>
  VSS33  = GND
  CA2_B  = M_F_CPU0_SB_CA<2>
  VSS34  = GND
  CA4_B  = M_F_CPU0_SB_CA<4>
  VSS35  = GND
  CA6_B  = M_F_CPU0_SB_CA<6>
  VSS36  = GND
  CS0_B_N  = M_F_CPU0_SB_CS_N<0>
  VSS37  = GND
  \lbd||rsp_a_n\  = M_F_CPU0_SA_RSP<0>
  \lbs||rsp_b_n\  = M_F_CPU0_SB_RSP<0>
  VSS38  = GND
  CB4_B  = M_F_CPU0_SB_CB<4>
  VSS39  = GND
  CB5_B  = M_F_CPU0_SB_CB<5>
  VSS40  = GND
  \dqs9_b_t||tdqs9_b_t||dbi4_b_n\  = M_F_CPU0_SB_DQS_DP<9>
  \dqs9_b_c||tdqs9_b_c\  = M_F_CPU0_SB_DQS_DN<9>
  VSS41  = GND
  CB0_B  = M_F_CPU0_SB_CB<0>
  VSS42  = GND
  CB1_B  = M_F_CPU0_SB_CB<1>
  VSS43  = GND
  DQ0_B  = M_F_CPU0_SB_DQ<0>
  VSS44  = GND
  DQ1_B  = M_F_CPU0_SB_DQ<1>
  VSS45  = GND
  DQS0_B_T  = M_F_CPU0_SB_DQS_DP<0>
  DQS0_B_C  = M_F_CPU0_SB_DQS_DN<0>
  VSS46  = GND
  DQ4_B  = M_F_CPU0_SB_DQ<4>
  VSS47  = GND
  DQ5_B  = M_F_CPU0_SB_DQ<5>
  VSS48  = GND
  DQ8_B  = M_F_CPU0_SB_DQ<8>
  VSS49  = GND
  DQ9_B  = M_F_CPU0_SB_DQ<9>
  VSS50  = GND
  DQS1_B_T  = M_F_CPU0_SB_DQS_DP<1>
  DQS1_B_C  = M_F_CPU0_SB_DQS_DN<1>
  VSS51  = GND
  DQ12_B  = M_F_CPU0_SB_DQ<12>
  VSS52  = GND
  DQ13_B  = M_F_CPU0_SB_DQ<13>
  VSS53  = GND
  DQ16_B  = M_F_CPU0_SB_DQ<16>
  VSS54  = GND
  DQ17_B  = M_F_CPU0_SB_DQ<17>
  VSS55  = GND
  DQS2_B_T  = M_F_CPU0_SB_DQS_DP<2>
  DQS2_B_C  = M_F_CPU0_SB_DQS_DN<2>
  VSS56  = GND
  DQ20_B  = M_F_CPU0_SB_DQ<20>
  VSS57  = GND
  DQ21_B  = M_F_CPU0_SB_DQ<21>
  VSS58  = GND
  DQ24_B  = M_F_CPU0_SB_DQ<24>
  VSS59  = GND
  DQ25_B  = M_F_CPU0_SB_DQ<25>
  VSS60  = GND
  DQS3_B_T  = M_F_CPU0_SB_DQS_DP<3>
  DQS3_B_C  = M_F_CPU0_SB_DQS_DN<3>
  VSS61  = GND
  DQ28_B  = M_F_CPU0_SB_DQ<28>
  VSS62  = GND
  DQ29_B  = M_F_CPU0_SB_DQ<29>
  VSS63  = GND
  RFU1  = TP_CHF_CPU0_DIMM1_FRU_1
  VIN_BULK1  = P12V_S3_AUX_CPU0_NVDIMM
  VIN_BULK2  = P12V_S3_AUX_CPU0_NVDIMM
  \pwr_good||fail_n\  = PWRGD_CHF_CPU0_DIMM1
  HSA  = PD_CHF_CPU0_DIMM1_SAA
  RFU2  = TP_CHF_CPU0_DIMM1_FRU_2
  RFU3  = TP_CHF_CPU0_DIMM1_FRU_3
  VSS64  = GND
  DQ2_A  = M_F_CPU0_SA_DQ<2>
  VSS65  = GND
  DQ3_A  = M_F_CPU0_SA_DQ<3>
  VSS66  = GND
  \dqs5_a_c||tdqs5_a_c||dqs5_a_t||tdqs5_a_t\  = M_F_CPU0_SA_DQS_DN<5>
  \dqs5_a_t||tdqs5_a_t\  = M_F_CPU0_SA_DQS_DP<5>
  VSS67  = GND
  DQ6_A  = M_F_CPU0_SA_DQ<6>
  VSS68  = GND
  DQ7_A  = M_F_CPU0_SA_DQ<7>
  VSS69  = GND
  DQ10_A  = M_F_CPU0_SA_DQ<10>
  VSS70  = GND
  DQ11_A  = M_F_CPU0_SA_DQ<11>
  VSS71  = GND
  \dqs6_a_c||tdqs6_a_c||dqs6_a_t||tdqs6_a_t\  = M_F_CPU0_SA_DQS_DN<6>
  \dqs6_a_t||tdqs6_a_t\  = M_F_CPU0_SA_DQS_DP<6>
  VSS72  = GND
  DQ14_A  = M_F_CPU0_SA_DQ<14>
  VSS73  = GND
  DQ15_A  = M_F_CPU0_SA_DQ<15>
  VSS74  = GND
  DQ18_A  = M_F_CPU0_SA_DQ<18>
  VSS75  = GND
  DQ19_A  = M_F_CPU0_SA_DQ<19>
  VSS76  = GND
  \dqs7_a_c||tdqs7_a_c\  = M_F_CPU0_SA_DQS_DN<7>
  \dqs7_a_t||tdqs7_a_t\  = M_F_CPU0_SA_DQS_DP<7>
  VSS77  = GND
  DQ22_A  = M_F_CPU0_SA_DQ<22>
  VSS78  = GND
  DQ23_A  = M_F_CPU0_SA_DQ<23>
  VSS79  = GND
  DQ26_A  = M_F_CPU0_SA_DQ<26>
  VSS80  = GND
  DQ27_A  = M_F_CPU0_SA_DQ<27>
  VSS81  = GND
  \dqs8_a_c||tdqs8_a_c\  = M_F_CPU0_SA_DQS_DN<8>
  \dqs8_a_t||tdqs8_a_t\  = M_F_CPU0_SA_DQS_DP<8>
  VSS82  = GND
  DQ30_A  = M_F_CPU0_SA_DQ<30>
  VSS83  = GND
  DQ31_A  = M_F_CPU0_SA_DQ<31>
  VSS84  = GND
  CB2_A  = M_F_CPU0_SA_CB<2>
  VSS85  = GND
  CB3_A  = M_F_CPU0_SA_CB<3>
  VSS86  = GND
  \dqs9_a_c||tdqs9_a_c\  = M_F_CPU0_SA_DQS_DN<9>
  \dqs9_a_t||tdqs9_a_t\  = M_F_CPU0_SA_DQS_DP<9>
  VSS87  = GND
  CB6_A  = M_F_CPU0_SA_CB<6>
  VSS88  = GND
  CB7_A  = M_F_CPU0_SA_CB<7>
  VSS89  = GND
  RESET_N  = RST_M_EF_CPU0_FPGA_N
  VSS90  = GND
  CS1_A_N  = M_F_CPU0_SA_CS_N<1>
  VSS91  = GND
  CA1_A  = M_F_CPU0_SA_CA<1>
  VSS92  = GND
  CA3_A  = M_F_CPU0_SA_CA<3>
  VSS93  = GND
  CA5_A  = M_F_CPU0_SA_CA<5>
  VSS94  = GND
  CK_T  = M_F_CPU0_CLK_DP<0>
  CK_C  = M_F_CPU0_CLK_DN<0>
  VSS95  = GND
  RFU4  = TP_CHF_CPU0_DIMM1_FRU_4
  CA1_B  = M_F_CPU0_SB_CA<1>
  VSS96  = GND
  CA3_B  = M_F_CPU0_SB_CA<3>
  VSS97  = GND
  CA5_B  = M_F_CPU0_SB_CA<5>
  VSS98  = GND
  PAR_B  = M_F_CPU0_SB_PAR
  VSS99  = GND
  CS1_B_N  = M_F_CPU0_SB_CS_N<1>
  VSS100  = GND
  RFU5  = TP_CHF_CPU0_DIMM1_FRU_5
  RFU6  = TP_CHF_CPU0_DIMM1_FRU_6
  VSS101  = GND
  CB6_B  = M_F_CPU0_SB_CB<6>
  VSS102  = GND
  CB7_B  = M_F_CPU0_SB_CB<7>
  VSS103  = GND
  DQS4_B_C  = M_F_CPU0_SB_DQS_DN<4>
  DQS4_B_T  = M_F_CPU0_SB_DQS_DP<4>
  VSS104  = GND
  CB2_B  = M_F_CPU0_SB_CB<2>
  VSS105  = GND
  CB3_B  = M_F_CPU0_SB_CB<3>
  VSS106  = GND
  DQ2_B  = M_F_CPU0_SB_DQ<2>
  VSS107  = GND
  DQ3_B  = M_F_CPU0_SB_DQ<3>
  VSS108  = GND
  \dqs5_b_c||tdqs5_b_c\  = M_F_CPU0_SB_DQS_DN<5>
  \dqs5_b_t||tdqs5_b_t\  = M_F_CPU0_SB_DQS_DP<5>
  VSS109  = GND
  DQ6_B  = M_F_CPU0_SB_DQ<6>
  VSS110  = GND
  DQ7_B  = M_F_CPU0_SB_DQ<7>
  VSS111  = GND
  DQ10_B  = M_F_CPU0_SB_DQ<10>
  VSS112  = GND
  DQ11_B  = M_F_CPU0_SB_DQ<11>
  VSS113  = GND
  \dqs6_b_c||tdqs6_b_c\  = M_F_CPU0_SB_DQS_DN<6>
  \dqs6_b_t||tdqs6_b_t\  = M_F_CPU0_SB_DQS_DP<6>
  VSS114  = GND
  DQ14_B  = M_F_CPU0_SB_DQ<14>
  VSS115  = GND
  DQ15_B  = M_F_CPU0_SB_DQ<15>
  VSS116  = GND
  DQ18_B  = M_F_CPU0_SB_DQ<18>
  VSS117  = GND
  DQ19_B  = M_F_CPU0_SB_DQ<19>
  VSS118  = GND
  \dqs7_b_c||tdqs7_b_c\  = M_F_CPU0_SB_DQS_DN<7>
  \dqs7_b_t||tdqs7_b_t\  = M_F_CPU0_SB_DQS_DP<7>
  VSS119  = GND
  DQ22_B  = M_F_CPU0_SB_DQ<22>
  VSS120  = GND
  DQ23_B  = M_F_CPU0_SB_DQ<23>
  VSS121  = GND
  DQ26_B  = M_F_CPU0_SB_DQ<26>
  VSS122  = GND
  DQ27_B  = M_F_CPU0_SB_DQ<27>
  VSS123  = GND
  \dqs8_b_c||tdqs8_b_c\  = M_F_CPU0_SB_DQS_DN<8>
  \dqs8_b_t||tdqs8_b_t\  = M_F_CPU0_SB_DQS_DP<8>
  VSS124  = GND
  DQ30_B  = M_F_CPU0_SB_DQ<30>
  VSS125  = GND
  DQ31_B  = M_F_CPU0_SB_DQ<31>
  VSS126  = GND
  G1  = GND
  G2  = GND
  G3  = GND

(kicad_pcb
	(version 20260206)
	(generator "pcbnew")
	(generator_version "10.0")
	(general
		(thickness 1.6)
		(legacy_teardrops no)
	)
	(paper "A4")
	(title_block
		(title "03242023_DA0F0TMBIJ0_F0T_Motherboard_J_brd_V01_OCP.brd")
		(comment 1 "Grand Teton / footprint 1952 of 6105 (J11), pads 138-182 of 291")
	)
	(layers
		(0 "F.Cu" signal "TOP")
		(4 "In1.Cu" signal "GND")
		(6 "In2.Cu" signal "IN1")
		(8 "In3.Cu" signal "GND1")
		(10 "In4.Cu" signal "IN2")
		(12 "In5.Cu" signal "GND2")
		(14 "In6.Cu" signal "IN3")
		(16 "In7.Cu" signal "GND3")
		(18 "In8.Cu" signal "VCC")
		(20 "In9.Cu" signal "VCC1")
		(22 "In10.Cu" signal "GND4")
		(24 "In11.Cu" signal "IN4")
		(26 "In12.Cu" signal "GND5")
		(28 "In13.Cu" signal "IN5")
		(30 "In14.Cu" signal "GND6")
		(32 "In15.Cu" signal "IN6")
		(34 "In16.Cu" signal "GND7")
		(2 "B.Cu" signal "BOTTOM")
		(9 "F.Adhes" user "F.Adhesive")
		(11 "B.Adhes" user "B.Adhesive")
		(13 "F.Paste" user "Package Geometry/Pastemask Top")
		(15 "B.Paste" user "Package Geometry/Pastemask Bottom")
		(5 "F.SilkS" user "Ref Des/Silkscreen Top")
		(7 "B.SilkS" user "Ref Des/Silkscreen Bottom")
		(1 "F.Mask" user "Board Geometry/Soldermask Top")
		(3 "B.Mask" user "Board Geometry/Soldermask Bottom")
		(17 "Dwgs.User" user "User.Drawings")
		(19 "Cmts.User" user "User.Comments")
		(21 "Eco1.User" user "User.Eco1")
		(23 "Eco2.User" user "User.Eco2")
		(25 "Edge.Cuts" user "Board Geometry/Outline")
		(27 "Margin" user)
		(31 "F.CrtYd" user "Package Geometry/Place Bound Top")
		(29 "B.CrtYd" user "Package Geometry/Place Bound Bottom")
		(35 "F.Fab" user "Ref Des/Assembly Top")
		(33 "B.Fab" user "Ref Des/Assembly Bottom")
	)
	(footprint ""
		(layer "F.Cu")
		(at 431.434748 -258.091686)
		(property "Reference" "J11"
			(at -3.683 -81.702148 0)
			(unlocked yes)
			(layer "F.SilkS")
			(effects
				(font
					(size 0.7874 0.5842)
					(thickness 0.1524)
				)
				(justify left)
			)
		)
		(property "Value" ""
			(at 0 0 0)
			(layer "F.Fab")
			(effects
				(font
					(size 1.27 1.27)
				)
			)
		)
		(duplicate_pad_numbers_are_jumpers no)
		(pad "138" smd rect
			(at -2.050034 58.224928 270)
			(size 0.519938 1.4986)
			(layers "F.Cu" "F.Mask" "F.Paste")
			(net "M_F_CPU0_SB_DQS_DN<3>")
		)
		(pad "139" smd rect
			(at -2.050034 59.075066 270)
			(size 0.519938 1.4986)
			(layers "F.Cu" "F.Mask" "F.Paste")
			(net "GND")
		)
		(pad "140" smd rect
			(at -2.050034 59.92495 270)
			(size 0.519938 1.4986)
			(layers "F.Cu" "F.Mask" "F.Paste")
			(net "M_F_CPU0_SB_DQ<28>")
		)
		(pad "141" smd rect
			(at -2.050034 60.775088 270)
			(size 0.519938 1.4986)
			(layers "F.Cu" "F.Mask" "F.Paste")
			(net "GND")
		)
		(pad "142" smd rect
			(at -2.050034 61.624972 270)
			(size 0.519938 1.4986)
			(layers "F.Cu" "F.Mask" "F.Paste")
			(net "M_F_CPU0_SB_DQ<29>")
		)
		(pad "143" smd rect
			(at -2.050034 62.47511 270)
			(size 0.519938 1.4986)
			(layers "F.Cu" "F.Mask" "F.Paste")
			(net "GND")
		)
		(pad "144" smd rect
			(at -2.050034 63.324994 270)
			(size 0.519938 1.4986)
			(layers "F.Cu" "F.Mask" "F.Paste")
			(net "TP_CHF_CPU0_DIMM1_FRU_1")
		)
		(pad "145" smd rect
			(at 2.050034 -63.324994 270)
			(size 0.519938 1.4986)
			(layers "F.Cu" "F.Mask" "F.Paste")
			(net "P12V_S3_AUX_CPU0_NVDIMM")
		)
		(pad "146" smd rect
			(at 2.050034 -62.47511 270)
			(size 0.519938 1.4986)
			(layers "F.Cu" "F.Mask" "F.Paste")
			(net "P12V_S3_AUX_CPU0_NVDIMM")
		)
		(pad "147" smd rect
			(at 2.050034 -61.624972 270)
			(size 0.519938 1.4986)
			(layers "F.Cu" "F.Mask" "F.Paste")
			(net "PWRGD_CHF_CPU0_DIMM1")
		)
		(pad "148" smd rect
			(at 2.050034 -60.775088 270)
			(size 0.519938 1.4986)
			(layers "F.Cu" "F.Mask" "F.Paste")
			(net "PD_CHF_CPU0_DIMM1_SAA")
		)
		(pad "149" smd rect
			(at 2.050034 -59.92495 270)
			(size 0.519938 1.4986)
			(layers "F.Cu" "F.Mask" "F.Paste")
			(net "TP_CHF_CPU0_DIMM1_FRU_2")
		)
		(pad "150" smd rect
			(at 2.050034 -59.075066 270)
			(size 0.519938 1.4986)
			(layers "F.Cu" "F.Mask" "F.Paste")
			(net "TP_CHF_CPU0_DIMM1_FRU_3")
		)
		(pad "151" smd rect
			(at 2.050034 -58.224928 270)
			(size 0.519938 1.4986)
			(layers "F.Cu" "F.Mask" "F.Paste")
			(net "GND")
		)
		(pad "152" smd rect
			(at 2.050034 -57.375044 270)
			(size 0.519938 1.4986)
			(layers "F.Cu" "F.Mask" "F.Paste")
			(net "M_F_CPU0_SA_DQ<2>")
		)
		(pad "153" smd rect
			(at 2.050034 -56.524906 270)
			(size 0.519938 1.4986)
			(layers "F.Cu" "F.Mask" "F.Paste")
			(net "GND")
		)
		(pad "154" smd rect
			(at 2.050034 -55.675022 270)
			(size 0.519938 1.4986)
			(layers "F.Cu" "F.Mask" "F.Paste")
			(net "M_F_CPU0_SA_DQ<3>")
		)
		(pad "155" smd rect
			(at 2.050034 -54.824884 270)
			(size 0.519938 1.4986)
			(layers "F.Cu" "F.Mask" "F.Paste")
			(net "GND")
		)
		(pad "156" smd rect
			(at 2.050034 -53.975 270)
			(size 0.519938 1.4986)
			(layers "F.Cu" "F.Mask" "F.Paste")
			(net "M_F_CPU0_SA_DQS_DN<5>")
		)
		(pad "157" smd rect
			(at 2.050034 -53.125116 270)
			(size 0.519938 1.4986)
			(layers "F.Cu" "F.Mask" "F.Paste")
			(net "M_F_CPU0_SA_DQS_DP<5>")
		)
		(pad "158" smd rect
			(at 2.050034 -52.274978 270)
			(size 0.519938 1.4986)
			(layers "F.Cu" "F.Mask" "F.Paste")
			(net "GND")
		)
		(pad "159" smd rect
			(at 2.050034 -51.425094 270)
			(size 0.519938 1.4986)
			(layers "F.Cu" "F.Mask" "F.Paste")
			(net "M_F_CPU0_SA_DQ<6>")
		)
		(pad "160" smd rect
			(at 2.050034 -50.574956 270)
			(size 0.519938 1.4986)
			(layers "F.Cu" "F.Mask" "F.Paste")
			(net "GND")
		)
		(pad "161" smd rect
			(at 2.050034 -49.725072 270)
			(size 0.519938 1.4986)
			(layers "F.Cu" "F.Mask" "F.Paste")
			(net "M_F_CPU0_SA_DQ<7>")
		)
		(pad "162" smd rect
			(at 2.050034 -48.874934 270)
			(size 0.519938 1.4986)
			(layers "F.Cu" "F.Mask" "F.Paste")
			(net "GND")
		)
		(pad "163" smd rect
			(at 2.050034 -48.02505 270)
			(size 0.519938 1.4986)
			(layers "F.Cu" "F.Mask" "F.Paste")
			(net "M_F_CPU0_SA_DQ<10>")
		)
		(pad "164" smd rect
			(at 2.050034 -47.174912 270)
			(size 0.519938 1.4986)
			(layers "F.Cu" "F.Mask" "F.Paste")
			(net "GND")
		)
		(pad "165" smd rect
			(at 2.050034 -46.325028 270)
			(size 0.519938 1.4986)
			(layers "F.Cu" "F.Mask" "F.Paste")
			(net "M_F_CPU0_SA_DQ<11>")
		)
		(pad "166" smd rect
			(at 2.050034 -45.47489 270)
			(size 0.519938 1.4986)
			(layers "F.Cu" "F.Mask" "F.Paste")
			(net "GND")
		)
		(pad "167" smd rect
			(at 2.050034 -44.625006 270)
			(size 0.519938 1.4986)
			(layers "F.Cu" "F.Mask" "F.Paste")
			(net "M_F_CPU0_SA_DQS_DN<6>")
		)
		(pad "168" smd rect
			(at 2.050034 -43.775122 270)
			(size 0.519938 1.4986)
			(layers "F.Cu" "F.Mask" "F.Paste")
			(net "M_F_CPU0_SA_DQS_DP<6>")
		)
		(pad "169" smd rect
			(at 2.050034 -42.924984 270)
			(size 0.519938 1.4986)
			(layers "F.Cu" "F.Mask" "F.Paste")
			(net "GND")
		)
		(pad "170" smd rect
			(at 2.050034 -42.0751 270)
			(size 0.519938 1.4986)
			(layers "F.Cu" "F.Mask" "F.Paste")
			(net "M_F_CPU0_SA_DQ<14>")
		)
		(pad "171" smd rect
			(at 2.050034 -41.224962 270)
			(size 0.519938 1.4986)
			(layers "F.Cu" "F.Mask" "F.Paste")
			(net "GND")
		)
		(pad "172" smd rect
			(at 2.050034 -40.375078 270)
			(size 0.519938 1.4986)
			(layers "F.Cu" "F.Mask" "F.Paste")
			(net "M_F_CPU0_SA_DQ<15>")
		)
		(pad "173" smd rect
			(at 2.050034 -39.52494 270)
			(size 0.519938 1.4986)
			(layers "F.Cu" "F.Mask" "F.Paste")
			(net "GND")
		)
		(pad "174" smd rect
			(at 2.050034 -38.675056 270)
			(size 0.519938 1.4986)
			(layers "F.Cu" "F.Mask" "F.Paste")
			(net "M_F_CPU0_SA_DQ<18>")
		)
		(pad "175" smd rect
			(at 2.050034 -37.824918 270)
			(size 0.519938 1.4986)
			(layers "F.Cu" "F.Mask" "F.Paste")
			(net "GND")
		)
		(pad "176" smd rect
			(at 2.050034 -36.975034 270)
			(size 0.519938 1.4986)
			(layers "F.Cu" "F.Mask" "F.Paste")
			(net "M_F_CPU0_SA_DQ<19>")
		)
		(pad "177" smd rect
			(at 2.050034 -36.124896 270)
			(size 0.519938 1.4986)
			(layers "F.Cu" "F.Mask" "F.Paste")
			(net "GND")
		)
		(pad "178" smd rect
			(at 2.050034 -35.275012 270)
			(size 0.519938 1.4986)
			(layers "F.Cu" "F.Mask" "F.Paste")
			(net "M_F_CPU0_SA_DQS_DN<7>")
		)
		(pad "179" smd rect
			(at 2.050034 -34.425128 270)
			(size 0.519938 1.4986)
			(layers "F.Cu" "F.Mask" "F.Paste")
			(net "M_F_CPU0_SA_DQS_DP<7>")
		)
		(pad "180" smd rect
			(at 2.050034 -33.57499 270)
			(size 0.519938 1.4986)
			(layers "F.Cu" "F.Mask" "F.Paste")
			(net "GND")
		)
		(pad "181" smd rect
			(at 2.050034 -32.725106 270)
			(size 0.519938 1.4986)
			(layers "F.Cu" "F.Mask" "F.Paste")
			(net "M_F_CPU0_SA_DQ<22>")
		)
		(pad "182" smd rect
			(at 2.050034 -31.874968 270)
			(size 0.519938 1.4986)
			(layers "F.Cu" "F.Mask" "F.Paste")
			(net "GND")
		)
	)
)
